# OCXO_DaughterCard_NoOscillator.xlsx — OCXO_DaughterCard_NoOscillator (bom)
| Comment | Description | Designator | Footprint | LibRef | Quantity |
| Yageo_RC0402FR-07100RL | RES SMD 100 OHM 1% 1/16W 0402 | R5 | RESC1005X040N | RES-CMP-00538-3 | 1 |
| Yageo_RC0201JR-070RL | RES, 0.0 OHM, 0.5A, 1/20W, 0201 | R33 | RESC0603X026N | CMP-RES-00843-1 | 1 |
| Yageo_RC0201FR-0710KL | RES, 10K OHM, 1%, 1/20W, 200PPM/C, 0201 | R34 | RESC0603X026N | CMP-RES-00602-1 | 1 |
| Yageo_CC0402KRX7R7BB103 | CAP, CER, X7R, 0.01UF, 10%, 16V, 0402, 0.55MM T | C12, C14 | CAPC1005X055N | CAP-CMP-00257-3 | 2 |
| Wurth_9774040243R | STANDOFF, ROUND, M2X0.4 STEEL 4MM, 9774040243R | J1, J2 | TH000V_300DIAx400_001mt_9774040243R | CON-CMP-00164-1 | 2 |
| TI_DS90LV028AQMA/NOPB | IC, RVCR, DS90LV028AQ-Q1, DUAL, DIFF, LVDS, 400MBPS, SOIC-8 | U4 | SOP127P600X175_8N | INT-CMP-00017-4 | 1 |
| TI_DS90LV027AQMA/NOPB | IC, DRIVER, DS90LV027AQ, DUAL, DIFF, LVDS, 600MBPS, SOIC-8 | U3 | SOP127P600X175_8N | INT-CMP-00018-2 | 1 |
| TDK_MPZ1608S601ATA00 | FERRITE BEAD, 600 OHM @100MHZ, 25%, 1A, 0.150 OHM DCR, 0603, 0.95MM T | FL1, FL2 | INDC1608X095N | FER-CMP-00057-5 | 2 |
| Stackpole Electronics, Inc._RMCF1210ZT0R00 | RES, 0.0 OHM, 3A, 1/2W, 1210 | R1 | RESC3225X070N | RES-CMP-00829-3 | 1 |
| Stackpole Electronics, Inc._HCJ0402ZT0R00 | RES, 0.0 OHM, 1/8W, 6.5A, 0402 | R6, R7, R8 | RESC1005X045N | RES-CMP-00382-3 | 3 |
| Samtec_HTSW-102-07-T-S | CONN, PIN, HEADER, 2POS, 2.54MM PITCH, 8.38MM H, VERT, TIN, TH | P9 | TH002_254_508x254x838_000mt_HTSW | CON-CMP-00061-3 | 1 |
| Samsung Electro-Mechanics_CL05B104JO5NNNC | CAP, CER, X7R, 0.1UF, 5%, 16V, 0402, 0.55MM T | C1, C6, C7, C9, C11, C13, C17, C19, C21, C23 | CAPC1005X055N | CAP-CMP-00271-3, CMP-CAP-00082-2 | 10 |
| Panasonic_ERJ-2RKF1003X | RES, 100K OHM, 1%, 1/10W, 100PPM/C, 0402 | R4 | RESC1005X040N | RES-CMP-00289-3 | 1 |
| NXP_PCT2075TP,147 | SENSOR DIGITAL -55C-125C 8HWSON | U5 | SON50P300X200X80-HS-9N_EP160x160_IPC | SNS-CMP-00004-1 | 1 |
| Murata_GRM188R61A106ME69D | CAP, CER, X5R, 10UF, 20%, 10V, 0603, 0.80MM T | C22 | CAPC1608X090N | CMP-CAP-00380-1 | 1 |
| Murata_GRM188D71A106MA73D | CAP, CER, X7T, 10UF, 20%, 10V, 0603, 1.00MM T | C8, C10, C18, C20 | CAPC1608X100N | CAP-CMP-00449-3 | 4 |
| Murata_GRM21BR61A226ME51L | CAP, CER, X5R, 22UF, 20%, 10V, 0805, 1.40MM T | C2, C3, C4 | CAPC2013X140N | CAP-CMP-00519-3 | 3 |
| Molex_539160208 | CONN, B2B/FPC, HEADER, 20-POS, 0.5MM PITCH, 4.0MM H, VERT, GOLD, SMT | P10 | SM020V_50_730x310x337_000mt_53916 | CON-CMP-00163-2 | 1 |
| Mill-Max_8600-0-05-80-00-00-03-0 | CONN, PC PIN, PRESS-FIT, 10.16MM LENGTH, TIN, TH | P1, P2, P3, P4, P5, P6, P7, P8, P11, P12 | TH001V_109DIA_000mt_8600-0 | CON-CMP-00162-1 | 10 |
| Microchip_AT24MAC602-XHM-B | IC, EEPROM, AT24MAC602, 2K-BIT (256 X 8), 1MHZ, I2C, 1.7V - 5.5V, TSSOP-8 | U2 | TSSOP65P640X120-8N | MEM-CMP-00010-1 | 1 |
| LMS1587IS-3.3/NOPB | 3A Low Dropout Fast Response Regulators, 3-pin TO-263, Pb-Free | U1 | KTT0003B_L | CMP-0062-00189-5 | 1 |
| Kemet_T491B476K010AT | CAP TANT 47UF 10% 10V 1411 | C5, C15, C16 | CAPMP3528X210N_T520 | CAP-CMP-00042-1 | 3 |
| 4871 | Round Standoff Threaded #2-56 Steel 0.063" (1.60mm) 1/16" | P13, P14, P15, P16 | Keystone_4871 | Keystone_4871 | 4 |
| 4.7K_1%_0402 | Chip Resistor, 4.7 KOhm, +/- 1%, 0.1 W, -55 to 155 degC, 0402 (1005 Metric), RoHS, Tape and Reel | R27, R28, R35, R36 | RESC1005X40X25LL05T05 | CMP-2002-01154-4 | 4 |
| 0_5%_0603 | Chip Resistor, 0 Ohm, +/- 5%, 0.1 W, -55 to 155 degC, 0603 (1608 Metric), RoHS, Tape and Reel | R16, R23 | RESC1608X55X25ML10T15 | CMP-2100-03667-1 | 2 |
| 0_1%_0402 |  | R11, R12, R17, R18, R19, R24, R25, R26, R30, R32 | RESC1005X40X25NL05T10 | CMP-1011-00001-2 | 10 |
